# T6G (Grand Teton) — schematic netlist excerpt (pin names and nets, part order shuffled) for the footprints in the layout excerpt that follows; sources: Cadence DE-HDL packaged netlist, KiCad conversion of 04192023_DAF0TMB3IC0_F0TG_MB_C_brd_V02_OCP.brd

PC114_3  Q_CAP  0.1UF 25V 10% X7R  pkg 0402  page 202 : A = PVDDCR_CPU1_P0_VCCS ; B = GND

PL35  Q_INDUCTOR4P_14  150NH IND  pkg L_TLM117513Q-151QL_11X7-5XA  page 215
  \1\  = SW_PVDDCR_SOC_P1_SW1
  \2\  = IND_SOC_P1_CPL2
  \3\  = GND
  \4\  = PVDDCR_SOC_P1

(kicad_pcb
	(version 20260206)
	(generator "pcbnew")
	(generator_version "10.0")
	(general
		(thickness 1.6)
		(legacy_teardrops no)
	)
	(paper "A4")
	(title_block
		(title "04192023_DAF0TMB3IC0_F0TG_MB_C_brd_V02_OCP.brd")
		(comment 1 "Grand Teton / footprints 4531-4532 of 8354")
	)
	(layers
		(0 "F.Cu" signal "TOP")
		(4 "In1.Cu" signal "GND")
		(6 "In2.Cu" signal "IN1")
		(8 "In3.Cu" signal "GND1")
		(10 "In4.Cu" signal "IN2")
		(12 "In5.Cu" signal "GND2")
		(14 "In6.Cu" signal "IN3")
		(16 "In7.Cu" signal "GND3")
		(18 "In8.Cu" signal "VCC")
		(20 "In9.Cu" signal "VCC1")
		(22 "In10.Cu" signal "GND4")
		(24 "In11.Cu" signal "IN4")
		(26 "In12.Cu" signal "GND5")
		(28 "In13.Cu" signal "IN5")
		(30 "In14.Cu" signal "GND6")
		(32 "In15.Cu" signal "IN6")
		(34 "In16.Cu" signal "GND7")
		(2 "B.Cu" signal "BOTTOM")
		(9 "F.Adhes" user "F.Adhesive")
		(11 "B.Adhes" user "B.Adhesive")
		(13 "F.Paste" user "Package Geometry/Pastemask Top")
		(15 "B.Paste" user "Package Geometry/Pastemask Bottom")
		(5 "F.SilkS" user "Ref Des/Silkscreen Top")
		(7 "B.SilkS" user "Ref Des/Silkscreen Bottom")
		(1 "F.Mask" user "Board Geometry/Soldermask Top")
		(3 "B.Mask" user "Board Geometry/Soldermask Bottom")
		(17 "Dwgs.User" user "User.Drawings")
		(19 "Cmts.User" user "User.Comments")
		(21 "Eco1.User" user "User.Eco1")
		(23 "Eco2.User" user "User.Eco2")
		(25 "Edge.Cuts" user "Board Geometry/Outline")
		(27 "Margin" user)
		(31 "F.CrtYd" user "Package Geometry/Place Bound Top")
		(29 "B.CrtYd" user "Package Geometry/Place Bound Bottom")
		(35 "F.Fab" user "Ref Des/Assembly Top")
		(33 "B.Fab" user "Ref Des/Assembly Bottom")
	)
	(footprint ""
		(layer "F.Cu")
		(at 116.10086 -181.240684 180)
		(property "Reference" "PL35"
			(at -0.781304 6.250178 0)
			(unlocked yes)
			(layer "F.SilkS")
			(effects
				(font
					(size 0.7874 0.5842)
					(thickness 0.1524)
				)
				(justify left)
			)
		)
		(property "Value" ""
			(at 0 0 180)
			(layer "F.Fab")
			(effects
				(font
					(size 1.27 1.27)
				)
			)
		)
		(duplicate_pad_numbers_are_jumpers no)
		(fp_line
			(start 3.750056 5.500116)
			(end 3.750056 -5.500116)
			(stroke
				(width 0.1524)
				(type default)
			)
			(layer "F.SilkS")
		)
		(fp_line
			(start 3.750056 -5.500116)
			(end 2.393442 -5.500116)
			(stroke
				(width 0.1524)
				(type default)
			)
			(layer "F.SilkS")
		)
		(fp_line
			(start 2.393442 5.500116)
			(end 3.750056 5.500116)
			(stroke
				(width 0.1524)
				(type default)
			)
			(layer "F.SilkS")
		)
		(fp_line
			(start -2.393442 5.500116)
			(end -3.750056 5.500116)
			(stroke
				(width 0.1524)
				(type default)
			)
			(layer "F.SilkS")
		)
		(fp_line
			(start -3.750056 5.500116)
			(end -3.750056 -5.500116)
			(stroke
				(width 0.1524)
				(type default)
			)
			(layer "F.SilkS")
		)
		(fp_line
			(start -3.750056 -5.500116)
			(end -2.393442 -5.500116)
			(stroke
				(width 0.1524)
				(type default)
			)
			(layer "F.SilkS")
		)
		(fp_poly
			(pts
				(xy -3.9116 -4.249928) (xy -4.3434 -4.034028) (xy -4.3434 -4.465828)
			)
			(stroke
				(width 0)
				(type default)
			)
			(fill yes)
			(layer "F.SilkS")
		)
		(fp_line
			(start 3.750056 5.500116)
			(end 3.750056 -5.500116)
			(stroke
				(width 0.1)
				(type default)
			)
			(layer "F.Fab")
		)
		(fp_line
			(start 3.750056 -5.500116)
			(end -3.750056 -5.500116)
			(stroke
				(width 0.1)
				(type default)
			)
			(layer "F.Fab")
		)
		(fp_line
			(start -3.750056 5.500116)
			(end 3.750056 5.500116)
			(stroke
				(width 0.1)
				(type default)
			)
			(layer "F.Fab")
		)
		(fp_line
			(start -3.750056 -5.500116)
			(end -3.750056 5.500116)
			(stroke
				(width 0.1)
				(type default)
			)
			(layer "F.Fab")
		)
		(fp_poly
			(pts
				(xy -4.9276 -4.757928) (xy -4.9276 -3.741928) (xy -3.9116 -4.249928)
			)
			(stroke
				(width 0)
				(type default)
			)
			(fill yes)
			(layer "F.Fab")
		)
		(pad "1" smd rect
			(at 0 -4.249928 90)
			(size 2.413 4.5212)
			(layers "F.Cu" "F.Mask" "F.Paste")
			(net "SW_PVDDCR_SOC_P1_SW1")
		)
		(pad "2" smd rect
			(at 0 -1.175004 90)
			(size 1.3716 4.5212)
			(layers "F.Cu" "F.Mask" "F.Paste")
			(net "IND_SOC_P1_CPL2")
		)
		(pad "3" smd rect
			(at 0 1.175004 90)
			(size 1.3716 4.5212)
			(layers "F.Cu" "F.Mask" "F.Paste")
			(net "GND")
		)
		(pad "4" smd rect
			(at 0 4.249928 90)
			(size 2.413 4.5212)
			(layers "F.Cu" "F.Mask" "F.Paste")
			(net "PVDDCR_SOC_P1")
		)
	)
	(footprint ""
		(layer "F.Cu")
		(at 315.651896 -339.852762 90)
		(property "Reference" "PC114_3"
			(at 0 0 90)
			(layer "F.SilkS")
			(hide yes)
			(effects
				(font
					(size 1.27 1.27)
				)
			)
		)
		(property "Value" ""
			(at 0 0 90)
			(layer "F.Fab")
			(effects
				(font
					(size 1.27 1.27)
				)
			)
		)
		(duplicate_pad_numbers_are_jumpers no)
		(fp_line
			(start 0.7874 -0.4064)
			(end 0.7874 0.4064)
			(stroke
				(width 0.1524)
				(type default)
			)
			(layer "F.SilkS")
		)
		(fp_line
			(start -0.7874 -0.4064)
			(end 0.7874 -0.4064)
			(stroke
				(width 0.1524)
				(type default)
			)
			(layer "F.SilkS")
		)
		(fp_line
			(start 0.7874 0.4064)
			(end -0.7874 0.4064)
			(stroke
				(width 0.1524)
				(type default)
			)
			(layer "F.SilkS")
		)
		(fp_line
			(start -0.7874 0.4064)
			(end -0.7874 -0.4064)
			(stroke
				(width 0.1524)
				(type default)
			)
			(layer "F.SilkS")
		)
		(fp_line
			(start -0.12065 -0.305054)
			(end -0.12065 -0.2794)
			(stroke
				(width 0.1)
				(type default)
			)
			(layer "F.Fab")
		)
		(fp_line
			(start -0.67945 -0.305054)
			(end -0.12065 -0.305054)
			(stroke
				(width 0.1)
				(type default)
			)
			(layer "F.Fab")
		)
		(fp_line
			(start 0.67945 -0.3048)
			(end 0.67945 0.3048)
			(stroke
				(width 0.1)
				(type default)
			)
			(layer "F.Fab")
		)
		(fp_line
			(start 0.12065 -0.3048)
			(end 0.67945 -0.3048)
			(stroke
				(width 0.1)
				(type default)
			)
			(layer "F.Fab")
		)
		(fp_line
			(start 0.12065 -0.2794)
			(end 0.12065 -0.3048)
			(stroke
				(width 0.1)
				(type default)
			)
			(layer "F.Fab")
		)
		(fp_line
			(start -0.12065 -0.2794)
			(end 0.12065 -0.2794)
			(stroke
				(width 0.1)
				(type default)
			)
			(layer "F.Fab")
		)
		(fp_line
			(start 0.120396 0.2794)
			(end -0.12065 0.2794)
			(stroke
				(width 0.1)
				(type default)
			)
			(layer "F.Fab")
		)
		(fp_line
			(start -0.12065 0.2794)
			(end -0.12065 0.3048)
			(stroke
				(width 0.1)
				(type default)
			)
			(layer "F.Fab")
		)
		(fp_line
			(start 0.67945 0.3048)
			(end 0.120396 0.3048)
			(stroke
				(width 0.1)
				(type default)
			)
			(layer "F.Fab")
		)
		(fp_line
			(start 0.120396 0.3048)
			(end 0.120396 0.2794)
			(stroke
				(width 0.1)
				(type default)
			)
			(layer "F.Fab")
		)
		(fp_line
			(start -0.12065 0.3048)
			(end -0.67945 0.3048)
			(stroke
				(width 0.1)
				(type default)
			)
			(layer "F.Fab")
		)
		(fp_line
			(start -0.67945 0.3048)
			(end -0.67945 -0.305054)
			(stroke
				(width 0.1)
				(type default)
			)
			(layer "F.Fab")
		)
		(pad "1" smd circle
			(at -0.40005 0 90)
			(size 0 0)
			(layers "F.Cu" "F.Mask" "F.Paste")
			(net "PVDDCR_CPU1_P0_VCCS")
		)
		(pad "2" smd circle
			(at 0.40005 0 90)
			(size 0 0)
			(layers "F.Cu" "F.Mask" "F.Paste")
			(net "GND")
		)
	)
)
